# S9S_MB_2U (Grand Teton) — schematic netlist excerpt (pin names and nets, part order shuffled) for the footprints in the layout excerpt that follows; sources: Cadence DE-HDL packaged netlist, KiCad conversion of 03242023_DA0F0TMBIJ0_F0T_Motherboard_J_brd_V01_OCP.brd

R4715  Q_RES  33.2 1% CHIP  pkg 0402LF  page 213 : A = SMB_HOST_3V3AUX_SCL_R4 ; B = SMB_HOST_3V3AUX_PLD_SCL

U157  74LVC1G07GV  IC  pkg SC-74A_2-9X1-5  page 155
  NC1  = NC_U157_NC1
  A  = OCP_SFF_WAKE_BUFF_R_N
  GND  = GND
  Y  = IRQ_LVC3_WAKE_BUF_N
  VCC  = P3V3_AUX

(kicad_pcb
	(version 20260206)
	(generator "pcbnew")
	(generator_version "10.0")
	(general
		(thickness 1.6)
		(legacy_teardrops no)
	)
	(paper "A4")
	(title_block
		(title "03242023_DA0F0TMBIJ0_F0T_Motherboard_J_brd_V01_OCP.brd")
		(comment 1 "Grand Teton / footprints 599-600 of 6105")
	)
	(layers
		(0 "F.Cu" signal "TOP")
		(4 "In1.Cu" signal "GND")
		(6 "In2.Cu" signal "IN1")
		(8 "In3.Cu" signal "GND1")
		(10 "In4.Cu" signal "IN2")
		(12 "In5.Cu" signal "GND2")
		(14 "In6.Cu" signal "IN3")
		(16 "In7.Cu" signal "GND3")
		(18 "In8.Cu" signal "VCC")
		(20 "In9.Cu" signal "VCC1")
		(22 "In10.Cu" signal "GND4")
		(24 "In11.Cu" signal "IN4")
		(26 "In12.Cu" signal "GND5")
		(28 "In13.Cu" signal "IN5")
		(30 "In14.Cu" signal "GND6")
		(32 "In15.Cu" signal "IN6")
		(34 "In16.Cu" signal "GND7")
		(2 "B.Cu" signal "BOTTOM")
		(9 "F.Adhes" user "F.Adhesive")
		(11 "B.Adhes" user "B.Adhesive")
		(13 "F.Paste" user "Package Geometry/Pastemask Top")
		(15 "B.Paste" user "Package Geometry/Pastemask Bottom")
		(5 "F.SilkS" user "Ref Des/Silkscreen Top")
		(7 "B.SilkS" user "Ref Des/Silkscreen Bottom")
		(1 "F.Mask" user "Board Geometry/Soldermask Top")
		(3 "B.Mask" user "Board Geometry/Soldermask Bottom")
		(17 "Dwgs.User" user "User.Drawings")
		(19 "Cmts.User" user "User.Comments")
		(21 "Eco1.User" user "User.Eco1")
		(23 "Eco2.User" user "User.Eco2")
		(25 "Edge.Cuts" user "Board Geometry/Outline")
		(27 "Margin" user)
		(31 "F.CrtYd" user "Package Geometry/Place Bound Top")
		(29 "B.CrtYd" user "Package Geometry/Place Bound Bottom")
		(35 "F.Fab" user "Ref Des/Assembly Top")
		(33 "B.Fab" user "Ref Des/Assembly Bottom")
	)
	(footprint ""
		(layer "F.Cu")
		(at 243.045488 -136.348724)
		(property "Reference" "R4715"
			(at 0 0 0)
			(layer "F.SilkS")
			(hide yes)
			(effects
				(font
					(size 1.27 1.27)
				)
			)
		)
		(property "Value" ""
			(at 0 0 0)
			(layer "F.Fab")
			(effects
				(font
					(size 1.27 1.27)
				)
			)
		)
		(duplicate_pad_numbers_are_jumpers no)
		(fp_line
			(start -0.7874 -0.4064)
			(end 0.7874 -0.4064)
			(stroke
				(width 0.1524)
				(type default)
			)
			(layer "F.SilkS")
		)
		(fp_line
			(start -0.7874 0.4064)
			(end -0.7874 -0.4064)
			(stroke
				(width 0.1524)
				(type default)
			)
			(layer "F.SilkS")
		)
		(fp_line
			(start 0.7874 -0.4064)
			(end 0.7874 0.4064)
			(stroke
				(width 0.1524)
				(type default)
			)
			(layer "F.SilkS")
		)
		(fp_line
			(start 0.7874 0.4064)
			(end -0.7874 0.4064)
			(stroke
				(width 0.1524)
				(type default)
			)
			(layer "F.SilkS")
		)
		(fp_line
			(start -0.67945 -0.305054)
			(end -0.12065 -0.305054)
			(stroke
				(width 0.1)
				(type default)
			)
			(layer "F.Fab")
		)
		(fp_line
			(start -0.67945 0.3048)
			(end -0.67945 -0.305054)
			(stroke
				(width 0.1)
				(type default)
			)
			(layer "F.Fab")
		)
		(fp_line
			(start -0.12065 -0.305054)
			(end -0.12065 -0.2794)
			(stroke
				(width 0.1)
				(type default)
			)
			(layer "F.Fab")
		)
		(fp_line
			(start -0.12065 -0.2794)
			(end 0.12065 -0.2794)
			(stroke
				(width 0.1)
				(type default)
			)
			(layer "F.Fab")
		)
		(fp_line
			(start -0.12065 0.2794)
			(end -0.12065 0.3048)
			(stroke
				(width 0.1)
				(type default)
			)
			(layer "F.Fab")
		)
		(fp_line
			(start -0.12065 0.3048)
			(end -0.67945 0.3048)
			(stroke
				(width 0.1)
				(type default)
			)
			(layer "F.Fab")
		)
		(fp_line
			(start 0.120396 0.2794)
			(end -0.12065 0.2794)
			(stroke
				(width 0.1)
				(type default)
			)
			(layer "F.Fab")
		)
		(fp_line
			(start 0.120396 0.3048)
			(end 0.120396 0.2794)
			(stroke
				(width 0.1)
				(type default)
			)
			(layer "F.Fab")
		)
		(fp_line
			(start 0.12065 -0.3048)
			(end 0.67945 -0.3048)
			(stroke
				(width 0.1)
				(type default)
			)
			(layer "F.Fab")
		)
		(fp_line
			(start 0.12065 -0.2794)
			(end 0.12065 -0.3048)
			(stroke
				(width 0.1)
				(type default)
			)
			(layer "F.Fab")
		)
		(fp_line
			(start 0.67945 -0.3048)
			(end 0.67945 0.3048)
			(stroke
				(width 0.1)
				(type default)
			)
			(layer "F.Fab")
		)
		(fp_line
			(start 0.67945 0.3048)
			(end 0.120396 0.3048)
			(stroke
				(width 0.1)
				(type default)
			)
			(layer "F.Fab")
		)
		(pad "1" smd circle
			(at -0.40005 0)
			(size 0 0)
			(layers "F.Cu" "F.Mask" "F.Paste")
			(net "SMB_HOST_3V3AUX_SCL_R4")
		)
		(pad "2" smd circle
			(at 0.40005 0)
			(size 0 0)
			(layers "F.Cu" "F.Mask" "F.Paste")
			(net "SMB_HOST_3V3AUX_PLD_SCL")
		)
	)
	(footprint ""
		(layer "F.Cu")
		(at 311.970674 -14.69136 180)
		(property "Reference" "U157"
			(at 1.306068 2.358644 0)
			(unlocked yes)
			(layer "F.SilkS")
			(effects
				(font
					(size 0.7874 0.5842)
					(thickness 0.1524)
				)
				(justify left)
			)
		)
		(property "Value" ""
			(at 0 0 180)
			(layer "F.Fab")
			(effects
				(font
					(size 1.27 1.27)
				)
			)
		)
		(duplicate_pad_numbers_are_jumpers no)
		(fp_line
			(start 1.733296 1.549908)
			(end 1.733296 -1.549908)
			(stroke
				(width 0.1524)
				(type default)
			)
			(layer "F.SilkS")
		)
		(fp_line
			(start 1.733296 -1.549908)
			(end 0.660908 -1.549908)
			(stroke
				(width 0.1524)
				(type default)
			)
			(layer "F.SilkS")
		)
		(fp_line
			(start 0.660908 -1.549908)
			(end 0 -0.889)
			(stroke
				(width 0.1524)
				(type default)
			)
			(layer "F.SilkS")
		)
		(fp_line
			(start 0 -0.889)
			(end -0.660908 -1.549908)
			(stroke
				(width 0.1524)
				(type default)
			)
			(layer "F.SilkS")
		)
		(fp_line
			(start -0.660908 -1.549908)
			(end -1.733296 -1.549908)
			(stroke
				(width 0.1524)
				(type default)
			)
			(layer "F.SilkS")
		)
		(fp_line
			(start -1.733296 1.549908)
			(end 1.733296 1.549908)
			(stroke
				(width 0.1524)
				(type default)
			)
			(layer "F.SilkS")
		)
		(fp_line
			(start -1.733296 -1.549908)
			(end -1.733296 1.549908)
			(stroke
				(width 0.1524)
				(type default)
			)
			(layer "F.SilkS")
		)
		(fp_poly
			(pts
				(xy -0.982218 -2.318766) (xy -1.236218 -1.810766) (xy -1.490218 -2.318766)
			)
			(stroke
				(width 0)
				(type default)
			)
			(fill yes)
			(layer "F.SilkS")
		)
		(fp_line
			(start 0.849884 1.549908)
			(end 0.849884 -1.549908)
			(stroke
				(width 0.1)
				(type default)
			)
			(layer "F.Fab")
		)
		(fp_line
			(start 0.849884 -1.549908)
			(end -0.849884 -1.549908)
			(stroke
				(width 0.1)
				(type default)
			)
			(layer "F.Fab")
		)
		(fp_line
			(start -0.849884 1.549908)
			(end 0.849884 1.549908)
			(stroke
				(width 0.1)
				(type default)
			)
			(layer "F.Fab")
		)
		(fp_line
			(start -0.849884 -1.549908)
			(end -0.849884 1.549908)
			(stroke
				(width 0.1)
				(type default)
			)
			(layer "F.Fab")
		)
		(fp_poly
			(pts
				(xy -2.4384 -1.20396) (xy -2.4384 -0.69596) (xy -1.9304 -0.94996)
			)
			(stroke
				(width 0)
				(type default)
			)
			(fill yes)
			(layer "F.Fab")
		)
		(pad "1" smd rect
			(at -1.199896 -0.94996 90)
			(size 0.5588 0.8128)
			(layers "F.Cu" "F.Mask" "F.Paste")
			(net "NC_U157_NC1")
		)
		(pad "2" smd rect
			(at -1.199896 0 90)
			(size 0.5588 0.8128)
			(layers "F.Cu" "F.Mask" "F.Paste")
			(net "OCP_SFF_WAKE_BUFF_R_N")
		)
		(pad "3" smd rect
			(at -1.199896 0.94996 90)
			(size 0.5588 0.8128)
			(layers "F.Cu" "F.Mask" "F.Paste")
			(net "GND")
		)
		(pad "4" smd rect
			(at 1.199896 0.94996 90)
			(size 0.5588 0.8128)
			(layers "F.Cu" "F.Mask" "F.Paste")
			(net "IRQ_LVC3_WAKE_BUF_N")
		)
		(pad "5" smd rect
			(at 1.199896 -0.94996 90)
			(size 0.5588 0.8128)
			(layers "F.Cu" "F.Mask" "F.Paste")
			(net "P3V3_AUX")
		)
	)
)
